# T6G (Grand Teton) — schematic parts with pin connectivity, parts 1539–1717 of 8303; source: Cadence DE-HDL packaged netlist (pstxprt.dat, pstxnet.dat, pstchip.dat)

C2273  Q_CAP  22UF 4V 20% X6S  pkg C0402  page 72 : 1 = PVDDCR_SOC_P1 ; 2 = GND
C2274  Q_CAP  22UF 4V 20% X6S  pkg C0402  page 72 : 1 = PVDDIO_P1 ; 2 = GND
C2275  Q_CAP  22UF 4V 20% X6S  pkg C0402  page 72 : 1 = PVDD11_S3_P1 ; 2 = GND
C2276  Q_CAP  22UF 4V 20% X6S  pkg C0402  page 72 : 1 = PVDDCR_SOC_P1 ; 2 = GND
C2277  Q_CAP  22UF 4V 20% X6S  pkg C0402  page 72 : 1 = PVDDCR_SOC_P1 ; 2 = GND
C2278  Q_CAP  22UF 4V 20% X6S  pkg C0402  page 72 : 1 = PVDDIO_P1 ; 2 = GND
C2279  Q_CAP  22UF 4V 20% X6S  pkg C0402  page 72 : 1 = PVDD11_S3_P1 ; 2 = GND
C2280  Q_CAP  22UF 4V 20% X6S  pkg C0402  page 72 : 1 = PVDDCR_SOC_P1 ; 2 = GND
C2281  Q_CAP  22UF 4V 20% X6S  pkg C0402  page 72 : 1 = PVDDCR_SOC_P1 ; 2 = GND
C2282  Q_CAP  22UF 4V 20% X6S  pkg C0402  page 72 : 1 = PVDD11_S3_P1 ; 2 = GND
C2283  Q_CAP  22UF 4V 20% X6S  pkg C0402  page 72 : 1 = PVDDCR_SOC_P1 ; 2 = GND
C2284  Q_CAP  22UF 4V 20% X6S  pkg C0402  page 72 : 1 = PVDDCR_SOC_P1 ; 2 = GND
C2285  Q_CAP  22UF 4V 20% X6S  pkg C0402  page 72 : 1 = PVDD11_S3_P1 ; 2 = GND
C2286  Q_CAP  22UF 4V 20% X6S  pkg C0402  page 72 : 1 = PVDDCR_SOC_P1 ; 2 = GND
C2287  Q_CAP  22UF 4V 20% X6S  pkg C0402  page 72 : 1 = PVDD11_S3_P1 ; 2 = GND
C2288  Q_CAP  22UF 4V 20% X6S  pkg C0402  page 72 : 1 = PVDDCR_SOC_P1 ; 2 = GND
C2289  Q_CAP  22UF 4V 20% X6S  pkg C0402  page 72 : 1 = PVDD11_S3_P1 ; 2 = GND
C2290  Q_CAP  22UF 4V 20% X6S  pkg C0402  page 72 : 1 = PVDDCR_SOC_P1 ; 2 = GND
C2291  Q_CAP  22UF 4V 20% X6S  pkg C0402  page 72 : 1 = PVDD11_S3_P1 ; 2 = GND
C2292  Q_CAP  22UF 4V 20% X6S  pkg C0402  page 72 : 1 = PVDD18_S5_P1 ; 2 = GND
C2293  Q_CAP  22UF 4V 20% X6S  pkg C0402  page 72 : 1 = PVDD18_S5_P1 ; 2 = GND
C2294  Q_CAP  22UF 4V 20% X6S  pkg C0402  page 73 : 1 = PVDDCR_CPU0_P1 ; 2 = GND
C2295  Q_CAP  22UF 4V 20% X6S  pkg C0402  page 73 : 1 = PVDDCR_CPU0_P1 ; 2 = GND
C2296  Q_CAP  22UF 4V 20% X6S  pkg C0402  page 73 : 1 = PVDDCR_CPU0_P1 ; 2 = GND
C2297  Q_CAP  22UF 4V 20% X6S  pkg C0402  page 73 : 1 = PVDDCR_CPU0_P1 ; 2 = GND
C2298  Q_CAP  22UF 4V 20% X6S  pkg C0402  page 73 : 1 = PVDDCR_CPU0_P1 ; 2 = GND
C2300  Q_CAP  22UF 4V 20% X6S  pkg C0402  page 73 : 1 = PVDDCR_CPU0_P1 ; 2 = GND
C2301  Q_CAP  22UF 4V 20% X6S  pkg C0402  page 73 : 1 = PVDDCR_CPU0_P1 ; 2 = GND
C2302  Q_CAP  22UF 4V 20% X6S  pkg C0402  page 73 : 1 = PVDDCR_CPU0_P1 ; 2 = GND
C2303  Q_CAP  22UF 4V 20% X6S  pkg C0402  page 73 : 1 = PVDDCR_CPU0_P1 ; 2 = GND
C2304  Q_CAP  22UF 4V 20% X6S  pkg C0402  page 73 : 1 = PVDDCR_CPU0_P1 ; 2 = GND
C2306  Q_CAP  22UF 4V 20% X6S  pkg C0402  page 73 : 1 = PVDDCR_CPU0_P1 ; 2 = GND
C2307  Q_CAP  22UF 4V 20% X6S  pkg C0402  page 73 : 1 = PVDDCR_CPU0_P1 ; 2 = GND
C2308  Q_CAP  22UF 4V 20% X6S  pkg C0402  page 73 : 1 = PVDDCR_CPU0_P1 ; 2 = GND
C2309  Q_CAP  22UF 4V 20% X6S  pkg C0402  page 73 : 1 = PVDDCR_CPU0_P1 ; 2 = GND
C2310  Q_CAP  22UF 4V 20% X6S  pkg C0402  page 73 : 1 = PVDDCR_CPU0_P1 ; 2 = GND
C2312  Q_CAP  22UF 4V 20% X6S  pkg C0402  page 73 : 1 = PVDDCR_CPU0_P1 ; 2 = GND
C2313  Q_CAP  22UF 4V 20% X6S  pkg C0402  page 73 : 1 = PVDDCR_CPU0_P1 ; 2 = GND
C2314  Q_CAP  22UF 4V 20% X6S  pkg C0402  page 73 : 1 = PVDDCR_CPU0_P1 ; 2 = GND
C2315  Q_CAP  22UF 4V 20% X6S  pkg C0402  page 73 : 1 = PVDDCR_CPU0_P1 ; 2 = GND
C2316  Q_CAP  22UF 4V 20% X6S  pkg C0402  page 73 : 1 = PVDDCR_CPU0_P1 ; 2 = GND
C2317  Q_CAP  1UF 25V 10% X6S  pkg C0402  page 176 : 1 = RST_USB_CPU0_HUB1_R_N ; 2 = GND
C2318  Q_CAP  22UF 4V 20% X6S  pkg C0402  page 73 : 1 = PVDDCR_CPU0_P1 ; 2 = GND
C2319  Q_CAP  22UF 4V 20% X6S  pkg C0402  page 73 : 1 = PVDDCR_CPU0_P1 ; 2 = GND
C2320  Q_CAP  22UF 4V 20% X6S  pkg C0402  page 73 : 1 = PVDDCR_CPU0_P1 ; 2 = GND
C2321  Q_CAP  22UF 4V 20% X6S  pkg C0402  page 73 : 1 = PVDDCR_CPU0_P1 ; 2 = GND
C2322  Q_CAP  22UF 4V 20% X6S  pkg C0402  page 73 : 1 = PVDDCR_CPU0_P1 ; 2 = GND
C2324  Q_CAP  22UF 4V 20% X6S  pkg C0402  page 73 : 1 = PVDDCR_CPU0_P1 ; 2 = GND
C2325  Q_CAP  22UF 4V 20% X6S  pkg C0402  page 73 : 1 = PVDDCR_CPU0_P1 ; 2 = GND
C2326  Q_CAP  22UF 4V 20% X6S  pkg C0402  page 73 : 1 = PVDDCR_CPU0_P1 ; 2 = GND
C2327  Q_CAP  22UF 4V 20% X6S  pkg C0402  page 73 : 1 = PVDDCR_CPU0_P1 ; 2 = GND
C2328  Q_CAP  10UF 6.3V 20% X6S  pkg C0402  page 182 : 1 = P3V3_9ZXL045_P0_VDD ; 2 = GND
C2329  Q_CAP  0.1UF 25V 10% X7R  pkg 0402  page 182 : 1 = P3V3_9ZXL045_P0_VDD ; 2 = GND
C2330  Q_CAP  22UF 4V 20% X6S  pkg C0402  page 73 : 1 = PVDDCR_CPU0_P1 ; 2 = GND
C2331  Q_CAP  22UF 4V 20% X6S  pkg C0402  page 73 : 1 = PVDDCR_CPU0_P1 ; 2 = GND
C2332  Q_CAP  22UF 4V 20% X6S  pkg C0402  page 73 : 1 = PVDDCR_CPU0_P1 ; 2 = GND
C2333  Q_CAP  22UF 4V 20% X6S  pkg C0402  page 73 : 1 = PVDDCR_CPU0_P1 ; 2 = GND
C2334  Q_CAP  0.1UF 25V 10% X7R  pkg 0402  page 182 : 1 = P3V3_9ZXL045_P0_VDDA ; 2 = GND
C2335  Q_CAP  22UF 4V 20% X6S  pkg C0402  page 73 : 1 = PVDDCR_CPU0_P1 ; 2 = GND
C2336  Q_CAP  22UF 4V 20% X6S  pkg C0402  page 73 : 1 = PVDDCR_CPU0_P1 ; 2 = GND
C2337  Q_CAP  22UF 4V 20% X6S  pkg C0402  page 73 : 1 = PVDDCR_CPU0_P1 ; 2 = GND
C2338  Q_CAP  22UF 4V 20% X6S  pkg C0402  page 73 : 1 = PVDDCR_CPU0_P1 ; 2 = GND
C2339  Q_CAP  0.1UF 25V 10% X7R  pkg 0402  page 182 : 1 = P3V3_9ZXL045_P0_VDD ; 2 = GND
C2340  Q_CAP  22UF 4V 20% X6S  pkg C0402  page 73 : 1 = PVDDCR_CPU0_P1 ; 2 = GND
C2341  Q_CAP  22UF 4V 20% X6S  pkg C0402  page 73 : 1 = PVDDCR_CPU0_P1 ; 2 = GND
C2342  Q_CAP  22UF 4V 20% X6S  pkg C0402  page 73 : 1 = PVDDCR_CPU0_P1 ; 2 = GND
C2343  Q_CAP  22UF 4V 20% X6S  pkg C0402  page 73 : 1 = PVDDCR_CPU0_P1 ; 2 = GND
C2344  Q_CAP  0.1UF 25V 10% X7R  pkg 0402  page 133 : 1 = P3V3_AUX ; 2 = GND
C2345  Q_CAP  22UF 4V 20% X6S  pkg C0402  page 73 : 1 = PVDDCR_CPU0_P1 ; 2 = GND
C2346  Q_CAP  22UF 4V 20% X6S  pkg C0402  page 73 : 1 = PVDDCR_CPU0_P1 ; 2 = GND
C2347  Q_CAP  22UF 4V 20% X6S  pkg C0402  page 73 : 1 = PVDDCR_CPU0_P1 ; 2 = GND
C2348  Q_CAP  22UF 4V 20% X6S  pkg C0402  page 73 : 1 = PVDDCR_CPU0_P1 ; 2 = GND
C2350  Q_CAP  22UF 4V 20% X6S  pkg C0402  page 73 : 1 = PVDDCR_CPU1_P1 ; 2 = GND
C2351  Q_CAP  22UF 4V 20% X6S  pkg C0402  page 73 : 1 = PVDDCR_CPU1_P1 ; 2 = GND
C2352  Q_CAP  22UF 4V 20% X6S  pkg C0402  page 73 : 1 = PVDDCR_CPU1_P1 ; 2 = GND
C2353  Q_CAP  22UF 4V 20% X6S  pkg C0402  page 73 : 1 = PVDDCR_CPU1_P1 ; 2 = GND
C2354  Q_CAP  22UF 4V 20% X6S  pkg C0402  page 73 : 1 = PVDDCR_CPU1_P1 ; 2 = GND
C2356  Q_CAP  22UF 4V 20% X6S  pkg C0402  page 73 : 1 = PVDDCR_CPU1_P1 ; 2 = GND
C2357  Q_CAP  22UF 4V 20% X6S  pkg C0402  page 73 : 1 = PVDDCR_CPU1_P1 ; 2 = GND
C2358  Q_CAP  22UF 4V 20% X6S  pkg C0402  page 73 : 1 = PVDDCR_CPU1_P1 ; 2 = GND
C2359  Q_CAP  22UF 4V 20% X6S  pkg C0402  page 73 : 1 = PVDDCR_CPU1_P1 ; 2 = GND
C2360  Q_CAP  22UF 4V 20% X6S  pkg C0402  page 73 : 1 = PVDDCR_CPU1_P1 ; 2 = GND
C2362  Q_CAP  22UF 4V 20% X6S  pkg C0402  page 73 : 1 = PVDDCR_CPU1_P1 ; 2 = GND
C2363  Q_CAP  22UF 4V 20% X6S  pkg C0402  page 73 : 1 = PVDDCR_CPU1_P1 ; 2 = GND
C2364  Q_CAP  22UF 4V 20% X6S  pkg C0402  page 73 : 1 = PVDDCR_CPU1_P1 ; 2 = GND
C2365  Q_CAP  22UF 4V 20% X6S  pkg C0402  page 73 : 1 = PVDDCR_CPU1_P1 ; 2 = GND
C2366  Q_CAP  22UF 4V 20% X6S  pkg C0402  page 73 : 1 = PVDDCR_CPU1_P1 ; 2 = GND
C2368  Q_CAP  22UF 4V 20% X6S  pkg C0402  page 73 : 1 = PVDDCR_CPU1_P1 ; 2 = GND
C2369  Q_CAP  22UF 4V 20% X6S  pkg C0402  page 73 : 1 = PVDDCR_CPU1_P1 ; 2 = GND
C2370  Q_CAP  22UF 4V 20% X6S  pkg C0402  page 73 : 1 = PVDDCR_CPU1_P1 ; 2 = GND
C2371  Q_CAP  22UF 4V 20% X6S  pkg C0402  page 73 : 1 = PVDDCR_CPU1_P1 ; 2 = GND
C2372  Q_CAP  22UF 4V 20% X6S  pkg C0402  page 73 : 1 = PVDDCR_CPU1_P1 ; 2 = GND
C2374  Q_CAP  22UF 4V 20% X6S  pkg C0402  page 73 : 1 = PVDDCR_CPU1_P1 ; 2 = GND
C2375  Q_CAP  22UF 4V 20% X6S  pkg C0402  page 73 : 1 = PVDDCR_CPU1_P1 ; 2 = GND
C2376  Q_CAP  22UF 4V 20% X6S  pkg C0402  page 73 : 1 = PVDDCR_CPU1_P1 ; 2 = GND
C2377  Q_CAP  22UF 4V 20% X6S  pkg C0402  page 73 : 1 = PVDDCR_CPU1_P1 ; 2 = GND
C2378  Q_CAP  22UF 4V 20% X6S  pkg C0402  page 73 : 1 = PVDDCR_CPU1_P1 ; 2 = GND
C2380  Q_CAP  22UF 4V 20% X6S  pkg C0402  page 73 : 1 = PVDDCR_CPU1_P1 ; 2 = GND
C2381  Q_CAP  22UF 4V 20% X6S  pkg C0402  page 73 : 1 = PVDDCR_CPU1_P1 ; 2 = GND
C2382  Q_CAP  22UF 4V 20% X6S  pkg C0402  page 73 : 1 = PVDDCR_CPU1_P1 ; 2 = GND
C2383  Q_CAP  22UF 4V 20% X6S  pkg C0402  page 73 : 1 = PVDDCR_CPU1_P1 ; 2 = GND
C2386  Q_CAP  22UF 4V 20% X6S  pkg C0402  page 73 : 1 = PVDDCR_CPU1_P1 ; 2 = GND
C2387  Q_CAP  22UF 4V 20% X6S  pkg C0402  page 73 : 1 = PVDDCR_CPU1_P1 ; 2 = GND
C2388  Q_CAP  22UF 4V 20% X6S  pkg C0402  page 73 : 1 = PVDDCR_CPU1_P1 ; 2 = GND
C2389  Q_CAP  22UF 4V 20% X6S  pkg C0402  page 73 : 1 = PVDDCR_CPU1_P1 ; 2 = GND
C2392  Q_CAP  22UF 4V 20% X6S  pkg C0402  page 73 : 1 = PVDDCR_CPU1_P1 ; 2 = GND
C2393  Q_CAP  22UF 4V 20% X6S  pkg C0402  page 73 : 1 = PVDDCR_CPU1_P1 ; 2 = GND
C2394  Q_CAP  22UF 4V 20% X6S  pkg C0402  page 73 : 1 = PVDDCR_CPU1_P1 ; 2 = GND
C2395  Q_CAP  22UF 4V 20% X6S  pkg C0402  page 73 : 1 = PVDDCR_CPU1_P1 ; 2 = GND
C2397  Q_CAP  22UF 4V 20% X6S  pkg C0402  page 73 : 1 = PVDDCR_CPU1_P1 ; 2 = GND
C2398  Q_CAP  22UF 4V 20% X6S  pkg C0402  page 73 : 1 = PVDDCR_CPU1_P1 ; 2 = GND
C2399  Q_CAP  22UF 4V 20% X6S  pkg C0402  page 73 : 1 = PVDDCR_CPU1_P1 ; 2 = GND
C2400  Q_CAP  22UF 4V 20% X6S  pkg C0402  page 73 : 1 = PVDDCR_CPU1_P1 ; 2 = GND
C2402  Q_CAP  22UF 4V 20% X6S  pkg C0402  page 73 : 1 = PVDDCR_CPU1_P1 ; 2 = GND
C2403  Q_CAP  22UF 4V 20% X6S  pkg C0402  page 73 : 1 = PVDDCR_CPU1_P1 ; 2 = GND
C2404  Q_CAP  22UF 4V 20% X6S  pkg C0402  page 73 : 1 = PVDDCR_CPU1_P1 ; 2 = GND
C2405  Q_CAP  22UF 4V 20% X6S  pkg C0402  page 73 : 1 = PVDDCR_CPU1_P1 ; 2 = GND
C2407  Q_CAP  22UF 4V 20% X6S  pkg C0402  page 74 : 1 = PVDDCR_SOC_P1 ; 2 = GND
C2408  Q_CAP  22UF 4V 20% X6S  pkg C0402  page 74 : 1 = PVDDCR_SOC_P1 ; 2 = GND
C2409  Q_CAP  22UF 4V 20% X6S  pkg C0402  page 74 : 1 = PVDDCR_SOC_P1 ; 2 = GND
C2410  Q_CAP  22UF 4V 20% X6S  pkg C0402  page 74 : 1 = PVDDCR_SOC_P1 ; 2 = GND
C2411  Q_CAP  22UF 4V 20% X6S  pkg C0402  page 74 : 1 = PVDDCR_SOC_P1 ; 2 = GND
C2412  Q_CAP  22UF 4V 20% X6S  pkg C0402  page 74 : 1 = PVDDCR_SOC_P1 ; 2 = GND
C2413  Q_CAP  22UF 4V 20% X6S  pkg C0402  page 74 : 1 = PVDDCR_SOC_P1 ; 2 = GND
C2414  Q_CAP  22UF 4V 20% X6S  pkg C0402  page 74 : 1 = PVDDCR_SOC_P1 ; 2 = GND
C2415  Q_CAP  22UF 4V 20% X6S  pkg C0402  page 74 : 1 = PVDDCR_SOC_P1 ; 2 = GND
C2416  Q_CAP  22UF 4V 20% X6S  pkg C0402  page 74 : 1 = PVDDCR_SOC_P1 ; 2 = GND
C2417  Q_CAP  22UF 4V 20% X6S  pkg C0402  page 74 : 1 = PVDDCR_SOC_P1 ; 2 = GND
C2418  Q_CAP  22UF 4V 20% X6S  pkg C0402  page 74 : 1 = PVDDCR_SOC_P1 ; 2 = GND
C2419  Q_CAP  22UF 4V 20% X6S  pkg C0402  page 74 : 1 = PVDDCR_SOC_P1 ; 2 = GND
C2420  Q_CAP  22UF 4V 20% X6S  pkg C0402  page 74 : 1 = PVDDCR_SOC_P1 ; 2 = GND
C2421  Q_CAP  22UF 4V 20% X6S  pkg C0402  page 74 : 1 = PVDDCR_SOC_P1 ; 2 = GND
C2422  Q_CAP  22UF 4V 20% X6S  pkg C0402  page 74 : 1 = PVDDCR_SOC_P1 ; 2 = GND
C2423  Q_CAP  22UF 4V 20% X6S  pkg C0402  page 74 : 1 = PVDDCR_SOC_P1 ; 2 = GND
C2424  Q_CAP  22UF 4V 20% X6S  pkg C0402  page 74 : 1 = PVDDCR_SOC_P1 ; 2 = GND
C2425  Q_CAP  22UF 4V 20% X6S  pkg C0402  page 74 : 1 = PVDDCR_SOC_P1 ; 2 = GND
C2426  Q_CAP  22UF 4V 20% X6S  pkg C0402  page 74 : 1 = PVDDCR_SOC_P1 ; 2 = GND
C2427  Q_CAP  22UF 4V 20% X6S  pkg C0402  page 74 : 1 = PVDDCR_SOC_P1 ; 2 = GND
C2428  Q_CAP  22UF 4V 20% X6S  pkg C0402  page 74 : 1 = PVDDCR_SOC_P1 ; 2 = GND
C2429  Q_CAP  22UF 4V 20% X6S  pkg C0402  page 74 : 1 = PVDDCR_SOC_P1 ; 2 = GND
C2430  Q_CAP  22UF 4V 20% X6S  pkg C0402  page 74 : 1 = PVDDCR_SOC_P1 ; 2 = GND
C2431  Q_CAP  22UF 4V 20% X6S  pkg C0402  page 74 : 1 = PVDDCR_SOC_P1 ; 2 = GND
C2432  Q_CAP  22UF 4V 20% X6S  pkg C0402  page 74 : 1 = PVDDCR_SOC_P1 ; 2 = GND
C2433  Q_CAP  22UF 4V 20% X6S  pkg C0402  page 74 : 1 = PVDDCR_SOC_P1 ; 2 = GND
C2434  Q_CAP  22UF 4V 20% X6S  pkg C0402  page 74 : 1 = PVDDCR_SOC_P1 ; 2 = GND
C2435  Q_CAP  22UF 4V 20% X6S  pkg C0402  page 74 : 1 = PVDDCR_SOC_P1 ; 2 = GND
C2436  Q_CAP  22UF 4V 20% X6S  pkg C0402  page 74 : 1 = PVDDCR_SOC_P1 ; 2 = GND
C2437  Q_CAP  22UF 4V 20% X6S  pkg C0402  page 74 : 1 = PVDDCR_SOC_P1 ; 2 = GND
C2438  Q_CAP  22UF 4V 20% X6S  pkg C0402  page 74 : 1 = PVDDCR_SOC_P1 ; 2 = GND
C2439  Q_CAP  22UF 4V 20% X6S  pkg C0402  page 74 : 1 = PVDDCR_SOC_P1 ; 2 = GND
C2440  Q_CAP  22UF 4V 20% X6S  pkg C0402  page 74 : 1 = PVDDCR_SOC_P1 ; 2 = GND
C2441  Q_CAP  22UF 4V 20% X6S  pkg C0402  page 74 : 1 = PVDDCR_SOC_P1 ; 2 = GND
C2442  Q_CAP  22UF 4V 20% X6S  pkg C0402  page 74 : 1 = PVDDCR_SOC_P1 ; 2 = GND
C2443  Q_CAP  22UF 4V 20% X6S  pkg C0402  page 74 : 1 = PVDDCR_SOC_P1 ; 2 = GND
C2444  Q_CAP  22UF 4V 20% X6S  pkg C0402  page 74 : 1 = PVDDCR_SOC_P1 ; 2 = GND
C2445  Q_CAP  22UF 4V 20% X6S  pkg C0402  page 74 : 1 = PVDDCR_SOC_P1 ; 2 = GND
C2446  Q_CAP  22UF 4V 20% X6S  pkg C0402  page 74 : 1 = PVDDCR_SOC_P1 ; 2 = GND
C2447  Q_CAP  22UF 4V 20% X6S  pkg C0402  page 74 : 1 = PVDDCR_SOC_P1 ; 2 = GND
C2448  Q_CAP  22UF 4V 20% X6S  pkg C0402  page 74 : 1 = PVDDCR_SOC_P1 ; 2 = GND
C2449  Q_CAP  22UF 4V 20% X6S  pkg C0402  page 74 : 1 = PVDDCR_SOC_P1 ; 2 = GND
C2450  Q_CAP  22UF 4V 20% X6S  pkg C0402  page 74 : 1 = PVDDCR_SOC_P1 ; 2 = GND
C2451  Q_CAP  22UF 4V 20% X6S  pkg C0402  page 74 : 1 = PVDDCR_SOC_P1 ; 2 = GND
C2452  Q_CAP  22UF 4V 20% X6S  pkg C0402  page 74 : 1 = PVDDCR_SOC_P1 ; 2 = GND
C2453  Q_CAP  22UF 4V 20% X6S  pkg C0402  page 74 : 1 = PVDDCR_SOC_P1 ; 2 = GND
C2454  Q_CAP  22UF 4V 20% X6S  pkg C0402  page 74 : 1 = PVDDCR_SOC_P1 ; 2 = GND
C2455  Q_CAP  22UF 4V 20% X6S  pkg C0402  page 74 : 1 = PVDDCR_SOC_P1 ; 2 = GND
C2456  Q_CAP  22UF 4V 20% X6S  pkg C0402  page 74 : 1 = PVDDCR_SOC_P1 ; 2 = GND
C2457  Q_CAP  22UF 4V 20% X6S  pkg C0402  page 74 : 1 = PVDDCR_SOC_P1 ; 2 = GND
C2458  Q_CAP  22UF 4V 20% X6S  pkg C0402  page 74 : 1 = PVDDCR_SOC_P1 ; 2 = GND
C2459  Q_CAP  22UF 4V 20% X6S  pkg C0402  page 74 : 1 = PVDDCR_SOC_P1 ; 2 = GND
C2460  Q_CAP  22UF 4V 20% X6S  pkg C0402  page 74 : 1 = PVDDCR_SOC_P1 ; 2 = GND
C2461  Q_CAP  22UF 4V 20% X6S  pkg C0402  page 74 : 1 = PVDDCR_SOC_P1 ; 2 = GND
C2462  Q_CAP  22UF 4V 20% X6S  pkg C0402  page 74 : 1 = PVDDCR_SOC_P1 ; 2 = GND
C2463  Q_CAP  22UF 4V 20% X6S  pkg C0402  page 74 : 1 = PVDDCR_SOC_P1 ; 2 = GND
C2464  Q_CAP  22UF 4V 20% X6S  pkg C0402  page 74 : 1 = PVDDCR_SOC_P1 ; 2 = GND
C2465  Q_CAP  22UF 4V 20% X6S  pkg C0402  page 74 : 1 = PVDDCR_SOC_P1 ; 2 = GND
C2466  Q_CAP  22UF 4V 20% X6S  pkg C0402  page 74 : 1 = PVDDCR_SOC_P1 ; 2 = GND
C2467  Q_CAP  22UF 4V 20% X6S  pkg C0402  page 74 : 1 = PVDDCR_SOC_P1 ; 2 = GND
C2468  Q_CAP  22UF 4V 20% X6S  pkg C0402  page 74 : 1 = PVDDCR_SOC_P1 ; 2 = GND
